(kicad_pcb
	(version 20260206)
	(generator "pcbnew")
	(generator_version "10.0")
	(general
		(thickness 1.6)
		(legacy_teardrops no)
	)
	(paper "A4")
	(title_block
		(title "dpb — 14545-sa.0730WZS0815.brd")
		(comment 1 "Honey Badger (Wiwynn) / footprints 679-685 of 1066")
	)
	(layers
		(0 "F.Cu" signal "TOP")
		(4 "In1.Cu" signal "L2GND")
		(6 "In2.Cu" signal "L3")
		(8 "In3.Cu" signal "L4VCC")
		(10 "In4.Cu" signal "L5VCC")
		(12 "In5.Cu" signal "L6")
		(14 "In6.Cu" signal "L7GND")
		(2 "B.Cu" signal "BOTTOM")
		(9 "F.Adhes" user "F.Adhesive")
		(11 "B.Adhes" user "B.Adhesive")
		(13 "F.Paste" user "Package Geometry/Pastemask Top")
		(15 "B.Paste" user "Package Geometry/Pastemask Bottom")
		(5 "F.SilkS" user "Ref Des/Silkscreen Top")
		(7 "B.SilkS" user "Ref Des/Silkscreen Bottom")
		(1 "F.Mask" user "Board Geometry/Soldermask Top")
		(3 "B.Mask" user "Board Geometry/Soldermask Bottom")
		(17 "Dwgs.User" user "User.Drawings")
		(19 "Cmts.User" user "User.Comments")
		(21 "Eco1.User" user "User.Eco1")
		(23 "Eco2.User" user "User.Eco2")
		(25 "Edge.Cuts" user "Board Geometry/Outline")
		(27 "Margin" user)
		(31 "F.CrtYd" user "Package Geometry/Place Bound Top")
		(29 "B.CrtYd" user "Package Geometry/Place Bound Bottom")
		(35 "F.Fab" user "Ref Des/Assembly Top")
		(33 "B.Fab" user "Ref Des/Assembly Bottom")
	)
	(footprint ""
		(layer "F.Cu")
		(at 190.930784 -184.120028 -90)
		(property "Reference" "R147"
			(at 0 0 270)
			(layer "F.SilkS")
			(hide yes)
			(effects
				(font
					(size 1.27 1.27)
				)
			)
		)
		(property "Value" "1KR2F-3-GP"
			(at 0.064008 -3.993896 270)
			(unlocked yes)
			(layer "F.Fab")
			(hide yes)
			(effects
				(font
					(size 1.016 1.016)
					(thickness 0.1524)
				)
			)
		)
		(property "Device Type" "R402H16"
			(at 0.064008 -5.517896 270)
			(unlocked yes)
			(layer "F.Fab")
			(hide yes)
			(effects
				(font
					(size 1.016 1.016)
					(thickness 0.1524)
				)
			)
		)
		(duplicate_pad_numbers_are_jumpers no)
		(fp_line
			(start -0.508 -0.9398)
			(end -0.508 0.9398)
			(stroke
				(width 0.1524)
				(type default)
			)
			(layer "F.SilkS")
		)
		(fp_line
			(start 0.508 -0.9398)
			(end -0.508 -0.9398)
			(stroke
				(width 0.1524)
				(type default)
			)
			(layer "F.SilkS")
		)
		(fp_rect
			(start -0.508 0.9398)
			(end 0.508 -0.9398)
			(stroke
				(width 0)
				(type default)
			)
			(fill no)
			(layer "F.CrtYd")
		)
		(fp_rect
			(start -0.508 0.9398)
			(end 0.508 -0.9398)
			(stroke
				(width 0)
				(type default)
			)
			(fill no)
			(layer "F.Fab")
		)
		(pad "1" smd custom
			(at 0 -0.4445 270)
			(size 0.1397 0.1397)
			(layers "F.Cu" "F.Mask" "F.Paste")
			(net "P3V3")
			(options
				(clearance outline)
				(anchor circle)
			)
			(primitives
				(gr_poly
					(pts
						(arc
							(start -0.1778 -0.2794)
							(mid -0.249642 -0.249642)
							(end -0.2794 -0.1778)
						)
						(arc
							(start -0.2794 0.1778)
							(mid -0.249642 0.249642)
							(end -0.1778 0.2794)
						)
						(arc
							(start 0.1778 0.2794)
							(mid 0.249642 0.249642)
							(end 0.2794 0.1778)
						)
						(arc
							(start 0.2794 -0.1778)
							(mid 0.249642 -0.249642)
							(end 0.1778 -0.2794)
						)
					)
					(width 0)
					(fill yes)
				)
			)
		)
		(pad "2" smd custom
			(at 0 0.4445 270)
			(size 0.1397 0.1397)
			(layers "F.Cu" "F.Mask" "F.Paste")
			(net "SW_PWR_HDD3")
			(options
				(clearance outline)
				(anchor circle)
			)
			(primitives
				(gr_poly
					(pts
						(arc
							(start -0.1778 -0.2794)
							(mid -0.249642 -0.249642)
							(end -0.2794 -0.1778)
						)
						(arc
							(start -0.2794 0.1778)
							(mid -0.249642 0.249642)
							(end -0.1778 0.2794)
						)
						(arc
							(start 0.1778 0.2794)
							(mid 0.249642 0.249642)
							(end 0.2794 0.1778)
						)
						(arc
							(start 0.2794 -0.1778)
							(mid 0.249642 -0.249642)
							(end 0.1778 -0.2794)
						)
					)
					(width 0)
					(fill yes)
				)
			)
		)
	)
	(footprint ""
		(layer "F.Cu")
		(at 14.731746 -258.3307 -90)
		(property "Reference" "R268"
			(at 0 0 270)
			(layer "F.SilkS")
			(hide yes)
			(effects
				(font
					(size 1.27 1.27)
				)
			)
		)
		(property "Value" "10KR2F-2-GP"
			(at 0.064008 -3.993896 270)
			(unlocked yes)
			(layer "F.Fab")
			(hide yes)
			(effects
				(font
					(size 1.016 1.016)
					(thickness 0.1524)
				)
			)
		)
		(property "Device Type" "R402H16"
			(at 0.064008 -5.517896 270)
			(unlocked yes)
			(layer "F.Fab")
			(hide yes)
			(effects
				(font
					(size 1.016 1.016)
					(thickness 0.1524)
				)
			)
		)
		(duplicate_pad_numbers_are_jumpers no)
		(fp_line
			(start -0.508 -0.9398)
			(end -0.508 0.9398)
			(stroke
				(width 0.1524)
				(type default)
			)
			(layer "F.SilkS")
		)
		(fp_line
			(start 0.508 -0.9398)
			(end -0.508 -0.9398)
			(stroke
				(width 0.1524)
				(type default)
			)
			(layer "F.SilkS")
		)
		(fp_rect
			(start -0.508 0.9398)
			(end 0.508 -0.9398)
			(stroke
				(width 0)
				(type default)
			)
			(fill no)
			(layer "F.CrtYd")
		)
		(fp_rect
			(start -0.508 0.9398)
			(end 0.508 -0.9398)
			(stroke
				(width 0)
				(type default)
			)
			(fill no)
			(layer "F.Fab")
		)
		(pad "1" smd custom
			(at 0 -0.4445 270)
			(size 0.1397 0.1397)
			(layers "F.Cu" "F.Mask" "F.Paste")
			(net "P5VC")
			(options
				(clearance outline)
				(anchor circle)
			)
			(primitives
				(gr_poly
					(pts
						(arc
							(start -0.1778 -0.2794)
							(mid -0.249642 -0.249642)
							(end -0.2794 -0.1778)
						)
						(arc
							(start -0.2794 0.1778)
							(mid -0.249642 0.249642)
							(end -0.1778 0.2794)
						)
						(arc
							(start 0.1778 0.2794)
							(mid 0.249642 0.249642)
							(end 0.2794 0.1778)
						)
						(arc
							(start 0.2794 -0.1778)
							(mid 0.249642 -0.249642)
							(end 0.1778 -0.2794)
						)
					)
					(width 0)
					(fill yes)
				)
			)
		)
		(pad "2" smd custom
			(at 0 0.4445 270)
			(size 0.1397 0.1397)
			(layers "F.Cu" "F.Mask" "F.Paste")
			(net "DRIVE_ACT_12")
			(options
				(clearance outline)
				(anchor circle)
			)
			(primitives
				(gr_poly
					(pts
						(arc
							(start -0.1778 -0.2794)
							(mid -0.249642 -0.249642)
							(end -0.2794 -0.1778)
						)
						(arc
							(start -0.2794 0.1778)
							(mid -0.249642 0.249642)
							(end -0.1778 0.2794)
						)
						(arc
							(start 0.1778 0.2794)
							(mid 0.249642 0.249642)
							(end 0.2794 0.1778)
						)
						(arc
							(start 0.2794 -0.1778)
							(mid 0.249642 -0.249642)
							(end 0.1778 -0.2794)
						)
					)
					(width 0)
					(fill yes)
				)
			)
		)
	)
	(footprint ""
		(layer "F.Cu")
		(at 52.705 -208.534)
		(property "Reference" "C391"
			(at 0 0 0)
			(layer "F.SilkS")
			(hide yes)
			(effects
				(font
					(size 1.27 1.27)
				)
			)
		)
		(property "Value" "SCD033U25V2KX-GP"
			(at 1.1811 -2.7051 0)
			(unlocked yes)
			(layer "F.Fab")
			(hide yes)
			(effects
				(font
					(size 1.016 1.016)
					(thickness 0.1524)
				)
			)
		)
		(property "Device Type" "C402H22"
			(at 1.1811 -4.2291 0)
			(unlocked yes)
			(layer "F.Fab")
			(hide yes)
			(effects
				(font
					(size 1.016 1.016)
					(thickness 0.1524)
				)
			)
		)
		(duplicate_pad_numbers_are_jumpers no)
		(fp_rect
			(start -0.4318 0.9525)
			(end 0.4318 -0.9525)
			(stroke
				(width 0)
				(type default)
			)
			(fill no)
			(layer "F.CrtYd")
		)
		(fp_rect
			(start -0.4318 0.9525)
			(end 0.4318 -0.9525)
			(stroke
				(width 0)
				(type default)
			)
			(fill no)
			(layer "F.Fab")
		)
		(pad "1" smd custom
			(at 0 -0.4445)
			(size 0.1524 0.1524)
			(layers "F.Cu" "F.Mask" "F.Paste")
			(net "P12V")
			(options
				(clearance outline)
				(anchor circle)
			)
			(primitives
				(gr_poly
					(pts
						(arc
							(start 0.3048 -0.2032)
							(mid 0.275042 -0.275042)
							(end 0.2032 -0.3048)
						)
						(arc
							(start -0.2032 -0.3048)
							(mid -0.275042 -0.275042)
							(end -0.3048 -0.2032)
						)
						(arc
							(start -0.3048 0.2032)
							(mid -0.275042 0.275042)
							(end -0.2032 0.3048)
						)
						(arc
							(start 0.2032 0.3048)
							(mid 0.275042 0.275042)
							(end 0.3048 0.2032)
						)
					)
					(width 0)
					(fill yes)
				)
			)
		)
		(pad "2" smd custom
			(at 0 0.4445)
			(size 0.1524 0.1524)
			(layers "F.Cu" "F.Mask" "F.Paste")
			(net "SW_HDD12_N")
			(options
				(clearance outline)
				(anchor circle)
			)
			(primitives
				(gr_poly
					(pts
						(arc
							(start 0.3048 -0.2032)
							(mid 0.275042 -0.275042)
							(end 0.2032 -0.3048)
						)
						(arc
							(start -0.2032 -0.3048)
							(mid -0.275042 -0.275042)
							(end -0.3048 -0.2032)
						)
						(arc
							(start -0.3048 0.2032)
							(mid -0.275042 0.275042)
							(end -0.2032 0.3048)
						)
						(arc
							(start 0.2032 0.3048)
							(mid 0.275042 0.275042)
							(end 0.3048 0.2032)
						)
					)
					(width 0)
					(fill yes)
				)
			)
		)
	)
	(footprint ""
		(layer "F.Cu")
		(at 5.079746 -491.7567 90)
		(property "Reference" "PR39"
			(at 0 0 90)
			(layer "F.SilkS")
			(hide yes)
			(effects
				(font
					(size 1.27 1.27)
				)
			)
		)
		(property "Value" "10KR2F-2-GP"
			(at 0.064008 -3.993896 90)
			(unlocked yes)
			(layer "F.Fab")
			(hide yes)
			(effects
				(font
					(size 1.016 1.016)
					(thickness 0.1524)
				)
			)
		)
		(property "Device Type" "R402H16"
			(at 0.064008 -5.517896 90)
			(unlocked yes)
			(layer "F.Fab")
			(hide yes)
			(effects
				(font
					(size 1.016 1.016)
					(thickness 0.1524)
				)
			)
		)
		(duplicate_pad_numbers_are_jumpers no)
		(fp_line
			(start 0.508 -0.9398)
			(end -0.508 -0.9398)
			(stroke
				(width 0.1524)
				(type default)
			)
			(layer "F.SilkS")
		)
		(fp_line
			(start -0.508 -0.9398)
			(end -0.508 0.9398)
			(stroke
				(width 0.1524)
				(type default)
			)
			(layer "F.SilkS")
		)
		(fp_rect
			(start -0.508 0.9398)
			(end 0.508 -0.9398)
			(stroke
				(width 0)
				(type default)
			)
			(fill no)
			(layer "F.CrtYd")
		)
		(fp_rect
			(start -0.508 0.9398)
			(end 0.508 -0.9398)
			(stroke
				(width 0)
				(type default)
			)
			(fill no)
			(layer "F.Fab")
		)
		(pad "1" smd custom
			(at 0 -0.4445 90)
			(size 0.1397 0.1397)
			(layers "F.Cu" "F.Mask" "F.Paste")
			(net "P5VC_VREG")
			(options
				(clearance outline)
				(anchor circle)
			)
			(primitives
				(gr_poly
					(pts
						(arc
							(start -0.1778 -0.2794)
							(mid -0.249642 -0.249642)
							(end -0.2794 -0.1778)
						)
						(arc
							(start -0.2794 0.1778)
							(mid -0.249642 0.249642)
							(end -0.1778 0.2794)
						)
						(arc
							(start 0.1778 0.2794)
							(mid 0.249642 0.249642)
							(end 0.2794 0.1778)
						)
						(arc
							(start 0.2794 -0.1778)
							(mid 0.249642 -0.249642)
							(end 0.1778 -0.2794)
						)
					)
					(width 0)
					(fill yes)
				)
			)
		)
		(pad "2" smd custom
			(at 0 0.4445 90)
			(size 0.1397 0.1397)
			(layers "F.Cu" "F.Mask" "F.Paste")
			(net "P5VC_PGD")
			(options
				(clearance outline)
				(anchor circle)
			)
			(primitives
				(gr_poly
					(pts
						(arc
							(start -0.1778 -0.2794)
							(mid -0.249642 -0.249642)
							(end -0.2794 -0.1778)
						)
						(arc
							(start -0.2794 0.1778)
							(mid -0.249642 0.249642)
							(end -0.1778 0.2794)
						)
						(arc
							(start 0.1778 0.2794)
							(mid 0.249642 0.249642)
							(end 0.2794 0.1778)
						)
						(arc
							(start 0.2794 -0.1778)
							(mid 0.249642 -0.249642)
							(end 0.1778 -0.2794)
						)
					)
					(width 0)
					(fill yes)
				)
			)
		)
	)
	(footprint ""
		(layer "F.Cu")
		(at 221.799912 -41.636696 90)
		(property "Reference" "R157"
			(at 0 0 90)
			(layer "F.SilkS")
			(hide yes)
			(effects
				(font
					(size 1.27 1.27)
				)
			)
		)
		(property "Value" "402R2F-GP"
			(at 0.064008 -3.993896 90)
			(unlocked yes)
			(layer "F.Fab")
			(hide yes)
			(effects
				(font
					(size 1.016 1.016)
					(thickness 0.1524)
				)
			)
		)
		(property "Device Type" "R402H16"
			(at 0.064008 -5.517896 90)
			(unlocked yes)
			(layer "F.Fab")
			(hide yes)
			(effects
				(font
					(size 1.016 1.016)
					(thickness 0.1524)
				)
			)
		)
		(duplicate_pad_numbers_are_jumpers no)
		(fp_line
			(start 0.508 -0.9398)
			(end -0.508 -0.9398)
			(stroke
				(width 0.1524)
				(type default)
			)
			(layer "F.SilkS")
		)
		(fp_line
			(start -0.508 -0.9398)
			(end -0.508 0.9398)
			(stroke
				(width 0.1524)
				(type default)
			)
			(layer "F.SilkS")
		)
		(fp_rect
			(start -0.508 0.9398)
			(end 0.508 -0.9398)
			(stroke
				(width 0)
				(type default)
			)
			(fill no)
			(layer "F.CrtYd")
		)
		(fp_rect
			(start -0.508 0.9398)
			(end 0.508 -0.9398)
			(stroke
				(width 0)
				(type default)
			)
			(fill no)
			(layer "F.Fab")
		)
		(pad "1" smd custom
			(at 0 -0.4445 90)
			(size 0.1397 0.1397)
			(layers "F.Cu" "F.Mask" "F.Paste")
			(net "P5VA_HDD4_LED")
			(options
				(clearance outline)
				(anchor circle)
			)
			(primitives
				(gr_poly
					(pts
						(arc
							(start -0.1778 -0.2794)
							(mid -0.249642 -0.249642)
							(end -0.2794 -0.1778)
						)
						(arc
							(start -0.2794 0.1778)
							(mid -0.249642 0.249642)
							(end -0.1778 0.2794)
						)
						(arc
							(start 0.1778 0.2794)
							(mid 0.249642 0.249642)
							(end 0.2794 0.1778)
						)
						(arc
							(start 0.2794 -0.1778)
							(mid 0.249642 -0.249642)
							(end 0.1778 -0.2794)
						)
					)
					(width 0)
					(fill yes)
				)
			)
		)
		(pad "2" smd custom
			(at 0 0.4445 90)
			(size 0.1397 0.1397)
			(layers "F.Cu" "F.Mask" "F.Paste")
			(net "DRV_ACT_4")
			(options
				(clearance outline)
				(anchor circle)
			)
			(primitives
				(gr_poly
					(pts
						(arc
							(start -0.1778 -0.2794)
							(mid -0.249642 -0.249642)
							(end -0.2794 -0.1778)
						)
						(arc
							(start -0.2794 0.1778)
							(mid -0.249642 0.249642)
							(end -0.1778 0.2794)
						)
						(arc
							(start 0.1778 0.2794)
							(mid 0.249642 0.249642)
							(end 0.2794 0.1778)
						)
						(arc
							(start 0.2794 -0.1778)
							(mid 0.249642 -0.249642)
							(end 0.1778 -0.2794)
						)
					)
					(width 0)
					(fill yes)
				)
			)
		)
	)
	(footprint ""
		(layer "F.Cu")
		(at 50.164746 -25.2857)
		(property "Reference" "PR23"
			(at 0 0 0)
			(layer "F.SilkS")
			(hide yes)
			(effects
				(font
					(size 1.27 1.27)
				)
			)
		)
		(property "Value" "10KR2F-2-GP"
			(at 0.064008 -3.993896 0)
			(unlocked yes)
			(layer "F.Fab")
			(hide yes)
			(effects
				(font
					(size 1.016 1.016)
					(thickness 0.1524)
				)
			)
		)
		(property "Device Type" "R402H16"
			(at 0.064008 -5.517896 0)
			(unlocked yes)
			(layer "F.Fab")
			(hide yes)
			(effects
				(font
					(size 1.016 1.016)
					(thickness 0.1524)
				)
			)
		)
		(duplicate_pad_numbers_are_jumpers no)
		(fp_line
			(start -0.508 -0.9398)
			(end -0.508 0.9398)
			(stroke
				(width 0.1524)
				(type default)
			)
			(layer "F.SilkS")
		)
		(fp_line
			(start 0.508 -0.9398)
			(end -0.508 -0.9398)
			(stroke
				(width 0.1524)
				(type default)
			)
			(layer "F.SilkS")
		)
		(fp_rect
			(start -0.508 0.9398)
			(end 0.508 -0.9398)
			(stroke
				(width 0)
				(type default)
			)
			(fill no)
			(layer "F.CrtYd")
		)
		(fp_rect
			(start -0.508 0.9398)
			(end 0.508 -0.9398)
			(stroke
				(width 0)
				(type default)
			)
			(fill no)
			(layer "F.Fab")
		)
		(pad "1" smd custom
			(at 0 -0.4445)
			(size 0.1397 0.1397)
			(layers "F.Cu" "F.Mask" "F.Paste")
			(net "P5VB_VREG")
			(options
				(clearance outline)
				(anchor circle)
			)
			(primitives
				(gr_poly
					(pts
						(arc
							(start -0.1778 -0.2794)
							(mid -0.249642 -0.249642)
							(end -0.2794 -0.1778)
						)
						(arc
							(start -0.2794 0.1778)
							(mid -0.249642 0.249642)
							(end -0.1778 0.2794)
						)
						(arc
							(start 0.1778 0.2794)
							(mid 0.249642 0.249642)
							(end 0.2794 0.1778)
						)
						(arc
							(start 0.2794 -0.1778)
							(mid 0.249642 -0.249642)
							(end 0.1778 -0.2794)
						)
					)
					(width 0)
					(fill yes)
				)
			)
		)
		(pad "2" smd custom
			(at 0 0.4445)
			(size 0.1397 0.1397)
			(layers "F.Cu" "F.Mask" "F.Paste")
			(net "P5VB_PGD")
			(options
				(clearance outline)
				(anchor circle)
			)
			(primitives
				(gr_poly
					(pts
						(arc
							(start -0.1778 -0.2794)
							(mid -0.249642 -0.249642)
							(end -0.2794 -0.1778)
						)
						(arc
							(start -0.2794 0.1778)
							(mid -0.249642 0.249642)
							(end -0.1778 0.2794)
						)
						(arc
							(start 0.1778 0.2794)
							(mid 0.249642 0.249642)
							(end 0.2794 0.1778)
						)
						(arc
							(start 0.2794 -0.1778)
							(mid 0.249642 -0.249642)
							(end 0.1778 -0.2794)
						)
					)
					(width 0)
					(fill yes)
				)
			)
		)
	)
	(footprint ""
		(layer "F.Cu")
		(at 33.019746 -63.2587 -90)
		(property "Reference" "C248"
			(at 0 0 270)
			(layer "F.SilkS")
			(hide yes)
			(effects
				(font
					(size 1.27 1.27)
				)
			)
		)
		(property "Value" "SCD01U50V2KX-1GP"
			(at 1.1811 -2.7051 270)
			(unlocked yes)
			(layer "F.Fab")
			(hide yes)
			(effects
				(font
					(size 1.016 1.016)
					(thickness 0.1524)
				)
			)
		)
		(property "Device Type" "C402H22"
			(at 1.1811 -4.2291 270)
			(unlocked yes)
			(layer "F.Fab")
			(hide yes)
			(effects
				(font
					(size 1.016 1.016)
					(thickness 0.1524)
				)
			)
		)
		(duplicate_pad_numbers_are_jumpers no)
		(fp_rect
			(start -0.4318 0.9525)
			(end 0.4318 -0.9525)
			(stroke
				(width 0)
				(type default)
			)
			(fill no)
			(layer "F.CrtYd")
		)
		(fp_rect
			(start -0.4318 0.9525)
			(end 0.4318 -0.9525)
			(stroke
				(width 0)
				(type default)
			)
			(fill no)
			(layer "F.Fab")
		)
		(pad "1" smd custom
			(at 0 -0.4445 270)
			(size 0.1524 0.1524)
			(layers "F.Cu" "F.Mask" "F.Paste")
			(net "SAS2X28_DRIVE_RX_N_B9")
			(options
				(clearance outline)
				(anchor circle)
			)
			(primitives
				(gr_poly
					(pts
						(arc
							(start 0.3048 -0.2032)
							(mid 0.275042 -0.275042)
							(end 0.2032 -0.3048)
						)
						(arc
							(start -0.2032 -0.3048)
							(mid -0.275042 -0.275042)
							(end -0.3048 -0.2032)
						)
						(arc
							(start -0.3048 0.2032)
							(mid -0.275042 0.275042)
							(end -0.2032 0.3048)
						)
						(arc
							(start 0.2032 0.3048)
							(mid 0.275042 0.275042)
							(end 0.3048 0.2032)
						)
					)
					(width 0)
					(fill yes)
				)
			)
		)
		(pad "2" smd custom
			(at 0 0.4445 270)
			(size 0.1524 0.1524)
			(layers "F.Cu" "F.Mask" "F.Paste")
			(net "SAS2X28_B_HDD9_RX_-")
			(options
				(clearance outline)
				(anchor circle)
			)
			(primitives
				(gr_poly
					(pts
						(arc
							(start 0.3048 -0.2032)
							(mid 0.275042 -0.275042)
							(end 0.2032 -0.3048)
						)
						(arc
							(start -0.2032 -0.3048)
							(mid -0.275042 -0.275042)
							(end -0.3048 -0.2032)
						)
						(arc
							(start -0.3048 0.2032)
							(mid -0.275042 0.275042)
							(end -0.2032 0.3048)
						)
						(arc
							(start 0.2032 0.3048)
							(mid 0.275042 0.275042)
							(end 0.3048 0.2032)
						)
					)
					(width 0)
					(fill yes)
				)
			)
		)
	)
)
